# SCM (Grand Teton) — schematic netlist excerpt (pin names and nets, part order shuffled) for the footprints in the layout excerpt that follows; sources: Cadence DE-HDL packaged netlist, KiCad conversion of 12092022_DA0F0TMDCD0_F0T_Management_Board_D_brd_V3_OCP.brd

R499  Q_RES  22 1% CHIP  pkg 0402LF  page 46 : A = SPI_SYS_R_MISO ; B = SPI_SYS_R1_MISO
R122  Q_RES  33.2 1% CHIP  pkg 0402LF  page 13 : A = FM_BIC_DEBUG_SW_N ; B = FM_BIC_DEBUG_SW_N_R

(kicad_pcb
	(version 20260206)
	(generator "pcbnew")
	(generator_version "10.0")
	(general
		(thickness 1.6)
		(legacy_teardrops no)
	)
	(paper "A4")
	(title_block
		(title "12092022_DA0F0TMDCD0_F0T_Management_Board_D_brd_V3_OCP.brd")
		(comment 1 "Grand Teton / footprints 94-95 of 1440")
	)
	(layers
		(0 "F.Cu" signal "TOP")
		(4 "In1.Cu" signal "GND")
		(6 "In2.Cu" signal "IN1")
		(8 "In3.Cu" signal "GND1")
		(10 "In4.Cu" signal "IN2")
		(12 "In5.Cu" signal "VCC")
		(14 "In6.Cu" signal "VCC1")
		(16 "In7.Cu" signal "IN3")
		(18 "In8.Cu" signal "GND2")
		(20 "In9.Cu" signal "IN4")
		(22 "In10.Cu" signal "GND3")
		(2 "B.Cu" signal "BOTTOM")
		(9 "F.Adhes" user "F.Adhesive")
		(11 "B.Adhes" user "B.Adhesive")
		(13 "F.Paste" user "Package Geometry/Pastemask Top")
		(15 "B.Paste" user "Package Geometry/Pastemask Bottom")
		(5 "F.SilkS" user "Ref Des/Silkscreen Top")
		(7 "B.SilkS" user "Ref Des/Silkscreen Bottom")
		(1 "F.Mask" user "Board Geometry/Soldermask Top")
		(3 "B.Mask" user "Board Geometry/Soldermask Bottom")
		(17 "Dwgs.User" user "User.Drawings")
		(19 "Cmts.User" user "User.Comments")
		(21 "Eco1.User" user "User.Eco1")
		(23 "Eco2.User" user "User.Eco2")
		(25 "Edge.Cuts" user "Board Geometry/Outline")
		(27 "Margin" user)
		(31 "F.CrtYd" user "Package Geometry/Place Bound Top")
		(29 "B.CrtYd" user "Package Geometry/Place Bound Bottom")
		(35 "F.Fab" user "Ref Des/Assembly Top")
		(33 "B.Fab" user "Ref Des/Assembly Bottom")
	)
	(footprint ""
		(layer "F.Cu")
		(at 68.189094 -96.79305 180)
		(property "Reference" "R499"
			(at 0 0 180)
			(layer "F.SilkS")
			(hide yes)
			(effects
				(font
					(size 1.27 1.27)
				)
			)
		)
		(property "Value" ""
			(at 0 0 180)
			(layer "F.Fab")
			(effects
				(font
					(size 1.27 1.27)
				)
			)
		)
		(duplicate_pad_numbers_are_jumpers no)
		(fp_line
			(start 0.7874 0.4064)
			(end -0.7874 0.4064)
			(stroke
				(width 0.1524)
				(type default)
			)
			(layer "F.SilkS")
		)
		(fp_line
			(start 0.7874 -0.4064)
			(end 0.7874 0.4064)
			(stroke
				(width 0.1524)
				(type default)
			)
			(layer "F.SilkS")
		)
		(fp_line
			(start -0.7874 0.4064)
			(end -0.7874 -0.4064)
			(stroke
				(width 0.1524)
				(type default)
			)
			(layer "F.SilkS")
		)
		(fp_line
			(start -0.7874 -0.4064)
			(end 0.7874 -0.4064)
			(stroke
				(width 0.1524)
				(type default)
			)
			(layer "F.SilkS")
		)
		(fp_line
			(start 0.67945 0.3048)
			(end 0.120396 0.3048)
			(stroke
				(width 0.1)
				(type default)
			)
			(layer "F.Fab")
		)
		(fp_line
			(start 0.67945 -0.3048)
			(end 0.67945 0.3048)
			(stroke
				(width 0.1)
				(type default)
			)
			(layer "F.Fab")
		)
		(fp_line
			(start 0.12065 -0.2794)
			(end 0.12065 -0.3048)
			(stroke
				(width 0.1)
				(type default)
			)
			(layer "F.Fab")
		)
		(fp_line
			(start 0.12065 -0.3048)
			(end 0.67945 -0.3048)
			(stroke
				(width 0.1)
				(type default)
			)
			(layer "F.Fab")
		)
		(fp_line
			(start 0.120396 0.3048)
			(end 0.120396 0.2794)
			(stroke
				(width 0.1)
				(type default)
			)
			(layer "F.Fab")
		)
		(fp_line
			(start 0.120396 0.2794)
			(end -0.12065 0.2794)
			(stroke
				(width 0.1)
				(type default)
			)
			(layer "F.Fab")
		)
		(fp_line
			(start -0.12065 0.3048)
			(end -0.67945 0.3048)
			(stroke
				(width 0.1)
				(type default)
			)
			(layer "F.Fab")
		)
		(fp_line
			(start -0.12065 0.2794)
			(end -0.12065 0.3048)
			(stroke
				(width 0.1)
				(type default)
			)
			(layer "F.Fab")
		)
		(fp_line
			(start -0.12065 -0.2794)
			(end 0.12065 -0.2794)
			(stroke
				(width 0.1)
				(type default)
			)
			(layer "F.Fab")
		)
		(fp_line
			(start -0.12065 -0.305054)
			(end -0.12065 -0.2794)
			(stroke
				(width 0.1)
				(type default)
			)
			(layer "F.Fab")
		)
		(fp_line
			(start -0.67945 0.3048)
			(end -0.67945 -0.305054)
			(stroke
				(width 0.1)
				(type default)
			)
			(layer "F.Fab")
		)
		(fp_line
			(start -0.67945 -0.305054)
			(end -0.12065 -0.305054)
			(stroke
				(width 0.1)
				(type default)
			)
			(layer "F.Fab")
		)
		(pad "1" smd circle
			(at -0.40005 0 180)
			(size 0 0)
			(layers "F.Cu" "F.Mask" "F.Paste")
			(net "SPI_SYS_R_MISO")
		)
		(pad "2" smd circle
			(at 0.40005 0 180)
			(size 0 0)
			(layers "F.Cu" "F.Mask" "F.Paste")
			(net "SPI_SYS_R1_MISO")
		)
	)
	(footprint ""
		(layer "F.Cu")
		(at 39.9796 -40.2082)
		(property "Reference" "R122"
			(at 0 0 0)
			(layer "F.SilkS")
			(hide yes)
			(effects
				(font
					(size 1.27 1.27)
				)
			)
		)
		(property "Value" ""
			(at 0 0 0)
			(layer "F.Fab")
			(effects
				(font
					(size 1.27 1.27)
				)
			)
		)
		(duplicate_pad_numbers_are_jumpers no)
		(fp_line
			(start -0.7874 -0.4064)
			(end 0.7874 -0.4064)
			(stroke
				(width 0.1524)
				(type default)
			)
			(layer "F.SilkS")
		)
		(fp_line
			(start -0.7874 0.4064)
			(end -0.7874 -0.4064)
			(stroke
				(width 0.1524)
				(type default)
			)
			(layer "F.SilkS")
		)
		(fp_line
			(start 0.7874 -0.4064)
			(end 0.7874 0.4064)
			(stroke
				(width 0.1524)
				(type default)
			)
			(layer "F.SilkS")
		)
		(fp_line
			(start 0.7874 0.4064)
			(end -0.7874 0.4064)
			(stroke
				(width 0.1524)
				(type default)
			)
			(layer "F.SilkS")
		)
		(fp_line
			(start -0.67945 -0.305054)
			(end -0.12065 -0.305054)
			(stroke
				(width 0.1)
				(type default)
			)
			(layer "F.Fab")
		)
		(fp_line
			(start -0.67945 0.3048)
			(end -0.67945 -0.305054)
			(stroke
				(width 0.1)
				(type default)
			)
			(layer "F.Fab")
		)
		(fp_line
			(start -0.12065 -0.305054)
			(end -0.12065 -0.2794)
			(stroke
				(width 0.1)
				(type default)
			)
			(layer "F.Fab")
		)
		(fp_line
			(start -0.12065 -0.2794)
			(end 0.12065 -0.2794)
			(stroke
				(width 0.1)
				(type default)
			)
			(layer "F.Fab")
		)
		(fp_line
			(start -0.12065 0.2794)
			(end -0.12065 0.3048)
			(stroke
				(width 0.1)
				(type default)
			)
			(layer "F.Fab")
		)
		(fp_line
			(start -0.12065 0.3048)
			(end -0.67945 0.3048)
			(stroke
				(width 0.1)
				(type default)
			)
			(layer "F.Fab")
		)
		(fp_line
			(start 0.120396 0.2794)
			(end -0.12065 0.2794)
			(stroke
				(width 0.1)
				(type default)
			)
			(layer "F.Fab")
		)
		(fp_line
			(start 0.120396 0.3048)
			(end 0.120396 0.2794)
			(stroke
				(width 0.1)
				(type default)
			)
			(layer "F.Fab")
		)
		(fp_line
			(start 0.12065 -0.3048)
			(end 0.67945 -0.3048)
			(stroke
				(width 0.1)
				(type default)
			)
			(layer "F.Fab")
		)
		(fp_line
			(start 0.12065 -0.2794)
			(end 0.12065 -0.3048)
			(stroke
				(width 0.1)
				(type default)
			)
			(layer "F.Fab")
		)
		(fp_line
			(start 0.67945 -0.3048)
			(end 0.67945 0.3048)
			(stroke
				(width 0.1)
				(type default)
			)
			(layer "F.Fab")
		)
		(fp_line
			(start 0.67945 0.3048)
			(end 0.120396 0.3048)
			(stroke
				(width 0.1)
				(type default)
			)
			(layer "F.Fab")
		)
		(pad "1" smd circle
			(at -0.40005 0)
			(size 0 0)
			(layers "F.Cu" "F.Mask" "F.Paste")
			(net "FM_BIC_DEBUG_SW_N")
		)
		(pad "2" smd circle
			(at 0.40005 0)
			(size 0 0)
			(layers "F.Cu" "F.Mask" "F.Paste")
			(net "FM_BIC_DEBUG_SW_N_R")
		)
	)
)
